(kicad_pcb
	(version 20260206)
	(generator "pcbnew")
	(generator_version "10.0")
	(general
		(thickness 1.6)
		(legacy_teardrops no)
	)
	(paper "A4")
	(title_block
		(title "01162023_DA0F0TEBIF0_F0T_Expander_BD_F_brd_V02_OCP.brd")
		(comment 1 "Grand Teton / footprints 1426-1432 of 9728")
	)
	(layers
		(0 "F.Cu" signal "TOP")
		(4 "In1.Cu" signal "GND")
		(6 "In2.Cu" signal "VCC")
		(8 "In3.Cu" signal "VCC1")
		(10 "In4.Cu" signal "GND1")
		(12 "In5.Cu" signal "IN1")
		(14 "In6.Cu" signal "GND2")
		(16 "In7.Cu" signal "IN2")
		(18 "In8.Cu" signal "GND3")
		(20 "In9.Cu" signal "IN3")
		(22 "In10.Cu" signal "GND4")
		(24 "In11.Cu" signal "IN4")
		(26 "In12.Cu" signal "GND5")
		(28 "In13.Cu" signal "IN5")
		(30 "In14.Cu" signal "GND6")
		(32 "In15.Cu" signal "IN6")
		(34 "In16.Cu" signal "GND7")
		(2 "B.Cu" signal "BOTTOM")
		(9 "F.Adhes" user "F.Adhesive")
		(11 "B.Adhes" user "B.Adhesive")
		(13 "F.Paste" user "Package Geometry/Pastemask Top")
		(15 "B.Paste" user "Package Geometry/Pastemask Bottom")
		(5 "F.SilkS" user "Ref Des/Silkscreen Top")
		(7 "B.SilkS" user "Ref Des/Silkscreen Bottom")
		(1 "F.Mask" user "Board Geometry/Soldermask Top")
		(3 "B.Mask" user "Board Geometry/Soldermask Bottom")
		(17 "Dwgs.User" user "User.Drawings")
		(19 "Cmts.User" user "User.Comments")
		(21 "Eco1.User" user "User.Eco1")
		(23 "Eco2.User" user "User.Eco2")
		(25 "Edge.Cuts" user "Board Geometry/Outline")
		(27 "Margin" user)
		(31 "F.CrtYd" user "Package Geometry/Place Bound Top")
		(29 "B.CrtYd" user "Package Geometry/Place Bound Bottom")
		(35 "F.Fab" user "Ref Des/Assembly Top")
		(33 "B.Fab" user "Ref Des/Assembly Bottom")
	)
	(footprint ""
		(layer "F.Cu")
		(at 378.841 -179.451)
		(property "Reference" "R4702"
			(at 0 0 0)
			(layer "F.SilkS")
			(hide yes)
			(effects
				(font
					(size 1.27 1.27)
				)
			)
		)
		(property "Value" ""
			(at 0 0 0)
			(layer "F.Fab")
			(effects
				(font
					(size 1.27 1.27)
				)
			)
		)
		(duplicate_pad_numbers_are_jumpers no)
		(fp_line
			(start -0.7874 -0.4064)
			(end 0.7874 -0.4064)
			(stroke
				(width 0.1524)
				(type default)
			)
			(layer "F.SilkS")
		)
		(fp_line
			(start -0.7874 0.4064)
			(end -0.7874 -0.4064)
			(stroke
				(width 0.1524)
				(type default)
			)
			(layer "F.SilkS")
		)
		(fp_line
			(start 0.7874 -0.4064)
			(end 0.7874 0.4064)
			(stroke
				(width 0.1524)
				(type default)
			)
			(layer "F.SilkS")
		)
		(fp_line
			(start 0.7874 0.4064)
			(end -0.7874 0.4064)
			(stroke
				(width 0.1524)
				(type default)
			)
			(layer "F.SilkS")
		)
		(fp_line
			(start -0.67945 -0.305054)
			(end -0.12065 -0.305054)
			(stroke
				(width 0.1)
				(type default)
			)
			(layer "F.Fab")
		)
		(fp_line
			(start -0.67945 0.3048)
			(end -0.67945 -0.305054)
			(stroke
				(width 0.1)
				(type default)
			)
			(layer "F.Fab")
		)
		(fp_line
			(start -0.12065 -0.305054)
			(end -0.12065 -0.2794)
			(stroke
				(width 0.1)
				(type default)
			)
			(layer "F.Fab")
		)
		(fp_line
			(start -0.12065 -0.2794)
			(end 0.12065 -0.2794)
			(stroke
				(width 0.1)
				(type default)
			)
			(layer "F.Fab")
		)
		(fp_line
			(start -0.12065 0.2794)
			(end -0.12065 0.3048)
			(stroke
				(width 0.1)
				(type default)
			)
			(layer "F.Fab")
		)
		(fp_line
			(start -0.12065 0.3048)
			(end -0.67945 0.3048)
			(stroke
				(width 0.1)
				(type default)
			)
			(layer "F.Fab")
		)
		(fp_line
			(start 0.120396 0.2794)
			(end -0.12065 0.2794)
			(stroke
				(width 0.1)
				(type default)
			)
			(layer "F.Fab")
		)
		(fp_line
			(start 0.120396 0.3048)
			(end 0.120396 0.2794)
			(stroke
				(width 0.1)
				(type default)
			)
			(layer "F.Fab")
		)
		(fp_line
			(start 0.12065 -0.3048)
			(end 0.67945 -0.3048)
			(stroke
				(width 0.1)
				(type default)
			)
			(layer "F.Fab")
		)
		(fp_line
			(start 0.12065 -0.2794)
			(end 0.12065 -0.3048)
			(stroke
				(width 0.1)
				(type default)
			)
			(layer "F.Fab")
		)
		(fp_line
			(start 0.67945 -0.3048)
			(end 0.67945 0.3048)
			(stroke
				(width 0.1)
				(type default)
			)
			(layer "F.Fab")
		)
		(fp_line
			(start 0.67945 0.3048)
			(end 0.120396 0.3048)
			(stroke
				(width 0.1)
				(type default)
			)
			(layer "F.Fab")
		)
		(pad "1" smd circle
			(at -0.40005 0)
			(size 0 0)
			(layers "F.Cu" "F.Mask" "F.Paste")
			(net "PCA9555_1_PEX1_A0")
		)
		(pad "2" smd circle
			(at 0.40005 0)
			(size 0 0)
			(layers "F.Cu" "F.Mask" "F.Paste")
			(net "P3V3_AUX")
		)
	)
	(footprint ""
		(layer "F.Cu")
		(at 348.477586 -254.55372 180)
		(property "Reference" "PC128"
			(at 0 0 180)
			(layer "F.SilkS")
			(hide yes)
			(effects
				(font
					(size 1.27 1.27)
				)
			)
		)
		(property "Value" ""
			(at 0 0 180)
			(layer "F.Fab")
			(effects
				(font
					(size 1.27 1.27)
				)
			)
		)
		(duplicate_pad_numbers_are_jumpers no)
		(fp_line
			(start 0.7874 0.4064)
			(end -0.7874 0.4064)
			(stroke
				(width 0.1524)
				(type default)
			)
			(layer "F.SilkS")
		)
		(fp_line
			(start 0.7874 -0.4064)
			(end 0.7874 0.4064)
			(stroke
				(width 0.1524)
				(type default)
			)
			(layer "F.SilkS")
		)
		(fp_line
			(start -0.7874 0.4064)
			(end -0.7874 -0.4064)
			(stroke
				(width 0.1524)
				(type default)
			)
			(layer "F.SilkS")
		)
		(fp_line
			(start -0.7874 -0.4064)
			(end 0.7874 -0.4064)
			(stroke
				(width 0.1524)
				(type default)
			)
			(layer "F.SilkS")
		)
		(fp_line
			(start 0.67945 0.3048)
			(end 0.120396 0.3048)
			(stroke
				(width 0.1)
				(type default)
			)
			(layer "F.Fab")
		)
		(fp_line
			(start 0.67945 -0.3048)
			(end 0.67945 0.3048)
			(stroke
				(width 0.1)
				(type default)
			)
			(layer "F.Fab")
		)
		(fp_line
			(start 0.12065 -0.2794)
			(end 0.12065 -0.3048)
			(stroke
				(width 0.1)
				(type default)
			)
			(layer "F.Fab")
		)
		(fp_line
			(start 0.12065 -0.3048)
			(end 0.67945 -0.3048)
			(stroke
				(width 0.1)
				(type default)
			)
			(layer "F.Fab")
		)
		(fp_line
			(start 0.120396 0.3048)
			(end 0.120396 0.2794)
			(stroke
				(width 0.1)
				(type default)
			)
			(layer "F.Fab")
		)
		(fp_line
			(start 0.120396 0.2794)
			(end -0.12065 0.2794)
			(stroke
				(width 0.1)
				(type default)
			)
			(layer "F.Fab")
		)
		(fp_line
			(start -0.12065 0.3048)
			(end -0.67945 0.3048)
			(stroke
				(width 0.1)
				(type default)
			)
			(layer "F.Fab")
		)
		(fp_line
			(start -0.12065 0.2794)
			(end -0.12065 0.3048)
			(stroke
				(width 0.1)
				(type default)
			)
			(layer "F.Fab")
		)
		(fp_line
			(start -0.12065 -0.2794)
			(end 0.12065 -0.2794)
			(stroke
				(width 0.1)
				(type default)
			)
			(layer "F.Fab")
		)
		(fp_line
			(start -0.12065 -0.305054)
			(end -0.12065 -0.2794)
			(stroke
				(width 0.1)
				(type default)
			)
			(layer "F.Fab")
		)
		(fp_line
			(start -0.67945 0.3048)
			(end -0.67945 -0.305054)
			(stroke
				(width 0.1)
				(type default)
			)
			(layer "F.Fab")
		)
		(fp_line
			(start -0.67945 -0.305054)
			(end -0.12065 -0.305054)
			(stroke
				(width 0.1)
				(type default)
			)
			(layer "F.Fab")
		)
		(pad "1" smd circle
			(at -0.40005 0 180)
			(size 0 0)
			(layers "F.Cu" "F.Mask" "F.Paste")
			(net "P0V8_PEX2_VREF")
		)
		(pad "2" smd circle
			(at 0.40005 0 180)
			(size 0 0)
			(layers "F.Cu" "F.Mask" "F.Paste")
			(net "GND")
		)
	)
	(footprint ""
		(layer "F.Cu")
		(at 35.766248 -343.952322 90)
		(property "Reference" "C178"
			(at 0 0 90)
			(layer "F.SilkS")
			(hide yes)
			(effects
				(font
					(size 1.27 1.27)
				)
			)
		)
		(property "Value" ""
			(at 0 0 90)
			(layer "F.Fab")
			(effects
				(font
					(size 1.27 1.27)
				)
			)
		)
		(duplicate_pad_numbers_are_jumpers no)
		(fp_line
			(start 0.299974 -0.150114)
			(end 0.299974 0.150114)
			(stroke
				(width 0.1)
				(type default)
			)
			(layer "F.Fab")
		)
		(fp_line
			(start -0.299974 -0.150114)
			(end 0.299974 -0.150114)
			(stroke
				(width 0.1)
				(type default)
			)
			(layer "F.Fab")
		)
		(fp_line
			(start 0.299974 0.150114)
			(end -0.299974 0.150114)
			(stroke
				(width 0.1)
				(type default)
			)
			(layer "F.Fab")
		)
		(fp_line
			(start -0.299974 0.150114)
			(end -0.299974 -0.150114)
			(stroke
				(width 0.1)
				(type default)
			)
			(layer "F.Fab")
		)
		(pad "1" smd rect
			(at -0.2667 0 90)
			(size 0.3048 0.381)
			(layers "F.Cu" "F.Mask" "F.Paste")
			(net "P5E_PEX0_STN7_TX_DN<119>")
		)
		(pad "2" smd rect
			(at 0.2667 0 90)
			(size 0.3048 0.381)
			(layers "F.Cu" "F.Mask" "F.Paste")
			(net "P5E_PEX0_STN7_TX_C_DN<119>")
		)
	)
	(footprint ""
		(layer "F.Cu")
		(at 252.325378 -42.849038 180)
		(property "Reference" "R601"
			(at 0 0 180)
			(layer "F.SilkS")
			(hide yes)
			(effects
				(font
					(size 1.27 1.27)
				)
			)
		)
		(property "Value" ""
			(at 0 0 180)
			(layer "F.Fab")
			(effects
				(font
					(size 1.27 1.27)
				)
			)
		)
		(duplicate_pad_numbers_are_jumpers no)
		(fp_line
			(start 0.7874 0.4064)
			(end -0.7874 0.4064)
			(stroke
				(width 0.1524)
				(type default)
			)
			(layer "F.SilkS")
		)
		(fp_line
			(start 0.7874 -0.4064)
			(end 0.7874 0.4064)
			(stroke
				(width 0.1524)
				(type default)
			)
			(layer "F.SilkS")
		)
		(fp_line
			(start -0.7874 0.4064)
			(end -0.7874 -0.4064)
			(stroke
				(width 0.1524)
				(type default)
			)
			(layer "F.SilkS")
		)
		(fp_line
			(start -0.7874 -0.4064)
			(end 0.7874 -0.4064)
			(stroke
				(width 0.1524)
				(type default)
			)
			(layer "F.SilkS")
		)
		(fp_line
			(start 0.67945 0.3048)
			(end 0.120396 0.3048)
			(stroke
				(width 0.1)
				(type default)
			)
			(layer "F.Fab")
		)
		(fp_line
			(start 0.67945 -0.3048)
			(end 0.67945 0.3048)
			(stroke
				(width 0.1)
				(type default)
			)
			(layer "F.Fab")
		)
		(fp_line
			(start 0.12065 -0.2794)
			(end 0.12065 -0.3048)
			(stroke
				(width 0.1)
				(type default)
			)
			(layer "F.Fab")
		)
		(fp_line
			(start 0.12065 -0.3048)
			(end 0.67945 -0.3048)
			(stroke
				(width 0.1)
				(type default)
			)
			(layer "F.Fab")
		)
		(fp_line
			(start 0.120396 0.3048)
			(end 0.120396 0.2794)
			(stroke
				(width 0.1)
				(type default)
			)
			(layer "F.Fab")
		)
		(fp_line
			(start 0.120396 0.2794)
			(end -0.12065 0.2794)
			(stroke
				(width 0.1)
				(type default)
			)
			(layer "F.Fab")
		)
		(fp_line
			(start -0.12065 0.3048)
			(end -0.67945 0.3048)
			(stroke
				(width 0.1)
				(type default)
			)
			(layer "F.Fab")
		)
		(fp_line
			(start -0.12065 0.2794)
			(end -0.12065 0.3048)
			(stroke
				(width 0.1)
				(type default)
			)
			(layer "F.Fab")
		)
		(fp_line
			(start -0.12065 -0.2794)
			(end 0.12065 -0.2794)
			(stroke
				(width 0.1)
				(type default)
			)
			(layer "F.Fab")
		)
		(fp_line
			(start -0.12065 -0.305054)
			(end -0.12065 -0.2794)
			(stroke
				(width 0.1)
				(type default)
			)
			(layer "F.Fab")
		)
		(fp_line
			(start -0.67945 0.3048)
			(end -0.67945 -0.305054)
			(stroke
				(width 0.1)
				(type default)
			)
			(layer "F.Fab")
		)
		(fp_line
			(start -0.67945 -0.305054)
			(end -0.12065 -0.305054)
			(stroke
				(width 0.1)
				(type default)
			)
			(layer "F.Fab")
		)
		(pad "1" smd circle
			(at -0.40005 0 180)
			(size 0 0)
			(layers "F.Cu" "F.Mask" "F.Paste")
			(net "P12V_SSD8_R")
		)
		(pad "2" smd circle
			(at 0.40005 0 180)
			(size 0 0)
			(layers "F.Cu" "F.Mask" "F.Paste")
			(net "P12V_SSD8_VIN_P")
		)
	)
	(footprint ""
		(layer "F.Cu")
		(at 197.273672 -343.952322 90)
		(property "Reference" "C2543"
			(at 0 0 90)
			(layer "F.SilkS")
			(hide yes)
			(effects
				(font
					(size 1.27 1.27)
				)
			)
		)
		(property "Value" ""
			(at 0 0 90)
			(layer "F.Fab")
			(effects
				(font
					(size 1.27 1.27)
				)
			)
		)
		(duplicate_pad_numbers_are_jumpers no)
		(fp_line
			(start 0.299974 -0.150114)
			(end 0.299974 0.150114)
			(stroke
				(width 0.1)
				(type default)
			)
			(layer "F.Fab")
		)
		(fp_line
			(start -0.299974 -0.150114)
			(end 0.299974 -0.150114)
			(stroke
				(width 0.1)
				(type default)
			)
			(layer "F.Fab")
		)
		(fp_line
			(start 0.299974 0.150114)
			(end -0.299974 0.150114)
			(stroke
				(width 0.1)
				(type default)
			)
			(layer "F.Fab")
		)
		(fp_line
			(start -0.299974 0.150114)
			(end -0.299974 -0.150114)
			(stroke
				(width 0.1)
				(type default)
			)
			(layer "F.Fab")
		)
		(pad "1" smd rect
			(at -0.2667 0 90)
			(size 0.3048 0.381)
			(layers "F.Cu" "F.Mask" "F.Paste")
			(net "P5E_PEX1_STN4_TX_DN<64>")
		)
		(pad "2" smd rect
			(at 0.2667 0 90)
			(size 0.3048 0.381)
			(layers "F.Cu" "F.Mask" "F.Paste")
			(net "P5E_PEX1_STN4_TX_C_DN<64>")
		)
	)
	(footprint ""
		(layer "F.Cu")
		(at 320.852292 -115.400836)
		(property "Reference" "R6031"
			(at 0 0 0)
			(layer "F.SilkS")
			(hide yes)
			(effects
				(font
					(size 1.27 1.27)
				)
			)
		)
		(property "Value" ""
			(at 0 0 0)
			(layer "F.Fab")
			(effects
				(font
					(size 1.27 1.27)
				)
			)
		)
		(duplicate_pad_numbers_are_jumpers no)
		(fp_line
			(start -0.7874 -0.4064)
			(end 0.7874 -0.4064)
			(stroke
				(width 0.1524)
				(type default)
			)
			(layer "F.SilkS")
		)
		(fp_line
			(start -0.7874 0.4064)
			(end -0.7874 -0.4064)
			(stroke
				(width 0.1524)
				(type default)
			)
			(layer "F.SilkS")
		)
		(fp_line
			(start 0.7874 -0.4064)
			(end 0.7874 0.4064)
			(stroke
				(width 0.1524)
				(type default)
			)
			(layer "F.SilkS")
		)
		(fp_line
			(start 0.7874 0.4064)
			(end -0.7874 0.4064)
			(stroke
				(width 0.1524)
				(type default)
			)
			(layer "F.SilkS")
		)
		(fp_line
			(start -0.67945 -0.305054)
			(end -0.12065 -0.305054)
			(stroke
				(width 0.1)
				(type default)
			)
			(layer "F.Fab")
		)
		(fp_line
			(start -0.67945 0.3048)
			(end -0.67945 -0.305054)
			(stroke
				(width 0.1)
				(type default)
			)
			(layer "F.Fab")
		)
		(fp_line
			(start -0.12065 -0.305054)
			(end -0.12065 -0.2794)
			(stroke
				(width 0.1)
				(type default)
			)
			(layer "F.Fab")
		)
		(fp_line
			(start -0.12065 -0.2794)
			(end 0.12065 -0.2794)
			(stroke
				(width 0.1)
				(type default)
			)
			(layer "F.Fab")
		)
		(fp_line
			(start -0.12065 0.2794)
			(end -0.12065 0.3048)
			(stroke
				(width 0.1)
				(type default)
			)
			(layer "F.Fab")
		)
		(fp_line
			(start -0.12065 0.3048)
			(end -0.67945 0.3048)
			(stroke
				(width 0.1)
				(type default)
			)
			(layer "F.Fab")
		)
		(fp_line
			(start 0.120396 0.2794)
			(end -0.12065 0.2794)
			(stroke
				(width 0.1)
				(type default)
			)
			(layer "F.Fab")
		)
		(fp_line
			(start 0.120396 0.3048)
			(end 0.120396 0.2794)
			(stroke
				(width 0.1)
				(type default)
			)
			(layer "F.Fab")
		)
		(fp_line
			(start 0.12065 -0.3048)
			(end 0.67945 -0.3048)
			(stroke
				(width 0.1)
				(type default)
			)
			(layer "F.Fab")
		)
		(fp_line
			(start 0.12065 -0.2794)
			(end 0.12065 -0.3048)
			(stroke
				(width 0.1)
				(type default)
			)
			(layer "F.Fab")
		)
		(fp_line
			(start 0.67945 -0.3048)
			(end 0.67945 0.3048)
			(stroke
				(width 0.1)
				(type default)
			)
			(layer "F.Fab")
		)
		(fp_line
			(start 0.67945 0.3048)
			(end 0.120396 0.3048)
			(stroke
				(width 0.1)
				(type default)
			)
			(layer "F.Fab")
		)
		(pad "1" smd circle
			(at -0.40005 0)
			(size 0 0)
			(layers "F.Cu" "F.Mask" "F.Paste")
			(net "HP_NIC5_EN")
		)
		(pad "2" smd circle
			(at 0.40005 0)
			(size 0 0)
			(layers "F.Cu" "F.Mask" "F.Paste")
			(net "P3V3_NIC5_CO_EN")
		)
	)
	(footprint ""
		(layer "F.Cu")
		(at 138.985244 -87.813642 180)
		(property "Reference" "R1562"
			(at 0 0 180)
			(layer "F.SilkS")
			(hide yes)
			(effects
				(font
					(size 1.27 1.27)
				)
			)
		)
		(property "Value" ""
			(at 0 0 180)
			(layer "F.Fab")
			(effects
				(font
					(size 1.27 1.27)
				)
			)
		)
		(duplicate_pad_numbers_are_jumpers no)
		(fp_line
			(start 0.7874 0.4064)
			(end -0.7874 0.4064)
			(stroke
				(width 0.1524)
				(type default)
			)
			(layer "F.SilkS")
		)
		(fp_line
			(start 0.7874 -0.4064)
			(end 0.7874 0.4064)
			(stroke
				(width 0.1524)
				(type default)
			)
			(layer "F.SilkS")
		)
		(fp_line
			(start -0.7874 0.4064)
			(end -0.7874 -0.4064)
			(stroke
				(width 0.1524)
				(type default)
			)
			(layer "F.SilkS")
		)
		(fp_line
			(start -0.7874 -0.4064)
			(end 0.7874 -0.4064)
			(stroke
				(width 0.1524)
				(type default)
			)
			(layer "F.SilkS")
		)
		(fp_line
			(start 0.67945 0.3048)
			(end 0.120396 0.3048)
			(stroke
				(width 0.1)
				(type default)
			)
			(layer "F.Fab")
		)
		(fp_line
			(start 0.67945 -0.3048)
			(end 0.67945 0.3048)
			(stroke
				(width 0.1)
				(type default)
			)
			(layer "F.Fab")
		)
		(fp_line
			(start 0.12065 -0.2794)
			(end 0.12065 -0.3048)
			(stroke
				(width 0.1)
				(type default)
			)
			(layer "F.Fab")
		)
		(fp_line
			(start 0.12065 -0.3048)
			(end 0.67945 -0.3048)
			(stroke
				(width 0.1)
				(type default)
			)
			(layer "F.Fab")
		)
		(fp_line
			(start 0.120396 0.3048)
			(end 0.120396 0.2794)
			(stroke
				(width 0.1)
				(type default)
			)
			(layer "F.Fab")
		)
		(fp_line
			(start 0.120396 0.2794)
			(end -0.12065 0.2794)
			(stroke
				(width 0.1)
				(type default)
			)
			(layer "F.Fab")
		)
		(fp_line
			(start -0.12065 0.3048)
			(end -0.67945 0.3048)
			(stroke
				(width 0.1)
				(type default)
			)
			(layer "F.Fab")
		)
		(fp_line
			(start -0.12065 0.2794)
			(end -0.12065 0.3048)
			(stroke
				(width 0.1)
				(type default)
			)
			(layer "F.Fab")
		)
		(fp_line
			(start -0.12065 -0.2794)
			(end 0.12065 -0.2794)
			(stroke
				(width 0.1)
				(type default)
			)
			(layer "F.Fab")
		)
		(fp_line
			(start -0.12065 -0.305054)
			(end -0.12065 -0.2794)
			(stroke
				(width 0.1)
				(type default)
			)
			(layer "F.Fab")
		)
		(fp_line
			(start -0.67945 0.3048)
			(end -0.67945 -0.305054)
			(stroke
				(width 0.1)
				(type default)
			)
			(layer "F.Fab")
		)
		(fp_line
			(start -0.67945 -0.305054)
			(end -0.12065 -0.305054)
			(stroke
				(width 0.1)
				(type default)
			)
			(layer "F.Fab")
		)
		(pad "1" smd circle
			(at -0.40005 0 180)
			(size 0 0)
			(layers "F.Cu" "F.Mask" "F.Paste")
			(net "P3V3_AUX")
		)
		(pad "2" smd circle
			(at 0.40005 0 180)
			(size 0 0)
			(layers "F.Cu" "F.Mask" "F.Paste")
			(net "SMB_BIC_I2C9_MUX0_SSD4_R_SDA")
		)
	)
)
